# Bryce Canyon_Storage_Controller_Card_Stackup.xlsx — Stack up_16316-1 (pcb-stackup)
|  |  |  |  |  |  | Version |  |  |  |  |  |  |  |  |  |  |  |  |  |  |  |  |  |  |  |  |  |  |  |  |  |  |  |  |  |  |  |  |  |  |  |  |  |  |  |  |  |  |  |
| Board Number: |  | 16316-1 |  |  |  | 02 |  |  |  |  |  |  |  |  |  |  |  |  |  |  |  |  |  |  |  |  |  |  |  |  |  |  |  |  |  |  |  |  |  |  |  |  |  |  |  |  |  |  |  |
| Project name: |  | Bryce Canyon |  |  |  |  |  |  |  |  |  |  |  |  |  |  |  |  |  |  |  |  |  |  |  |  |  |  |  |  |  |  |  |  |  |  |  |  |  |  |  |  |  |  |  |  |  |  |  |
| Model Name: |  | Storage Controller Card |  |  |  |  |  |  |  |  |  |  |  |  |  |  |  |  |  |  |  |  |  |  |  |  |  |  |  |  |  |  |  |  |  |  |  |  |  |  |  |  |  |  |  |  |  |  |  |
| Layer Count: |  | 8 Layer |  |  |  |  |  |  |  |  |  |  |  |  |  |  |  |  |  |  |  |  |  |  |  |  |  |  |  |  |  |  |  |  |  |  |  |  |  |  |  |  |  |  |  |  |  |  |  |
| Date: |  | 2017-09-25 00:00:00 |  |  |  |  |  |  |  |  |  |  |  |  |  |  |  |  |  |  |  |  |  |  |  |  |  |  |  |  |  |  |  |  |  |  |  |  |  |  |  |  |  |  |  |  |  |  |  |
| Low Loss Material: |  | TU863+VLP (Tg : 180/Td : 375) |  |  |  |  |  |  | Single Ended Type(mil) |  |  |  |  | Differential Type(mil) |  |  |  |  |  |  |  |  |  |  |  |  |  |  |  |  |  |  |  |  |  |  |  |  |  |  |  |  |  |  |  |  |  |  |  |
| Gold Finger(Y/N): |  | N |  |  |  |  |  | Imp | 50 |  |  |  | Imp | 85 |  |  |  |  |  | 100 |  |  |  |  |  | 97 |  |  |  |  |  | 88 |  |  |  |  |  | 92 |  |  |  |  |  | 83 |  |  |  |  |  |
| Customer: |  | <name> |  |  |  |  |  | Variation | Inner/Outer+/-5ohm |  |  |  | Variation | Inner/Outer+/-10% |  |  |  |  |  | Inner/Outer+/-10% |  |  |  |  |  | Outer+/-10% |  |  |  |  |  | Inner+/-10% |  |  |  |  |  | Outer+/-10% |  |  |  |  |  | Inner+/-10% |  |  |  |  |  |
| EE engineer |  | <name> |  |  |  |  |  | Bus | MISC./I2C |  |  |  | Bus | PCIe/Clock/USB |  |  |  |  |  | Clock/SATA |  |  |  |  |  | BGA Break out(SAS.SATA) |  |  |  |  |  | BGA Break out(SAS.SATA) |  |  |  |  |  | BGA Break out(PCIE) |  |  |  |  |  | BGA Break out(PCIE) |  |  |  |  |  |
| SI Engineer |  | <name> |  |  |  |  |  |  |  |  |  |  |  |  |  |  |  |  |  |  |  |  |  |  |  |  |  |  |  |  |  |  |  |  |  |  |  |  |  |  |  |  |  |  |  |  |  |  |  |
|  |  |  |  |  |  |  |  | Type | SE |  |  |  | Type | DP |  |  |  |  |  | DP |  |  |  |  |  | DP |  |  |  |  |  | DP |  |  |  |  |  | DP |  |  |  |  |  | DP |  |  |  |  |  |
| Layer |  |  | Thickness |  | Glass/Copper Style | Er | Df(1G) | Layers | 1,3,6,8 |  |  |  | Layers | 1,3,6,8 |  |  |  |  |  | 1,3,6,8 |  |  |  |  |  | 1,8 |  |  |  |  |  | 3,6 |  |  |  |  |  | 1,8 |  |  |  |  |  | 3,6 |  |  |  |  |  |
|  |  | Cu oz | Wiwynn |  |  | Wiwynn |  |  | Wiwynn |  |  |  |  | Wiwynn |  |  |  |  |  | Wiwynn |  |  |  |  |  | Wiwynn |  |  |  |  |  | Wiwynn |  |  |  |  |  | Wiwynn |  |  |  |  |  | Wiwynn |  |  |  |  |  |
|  | Mask |  | 0.5 |  |  | 3.4 | 0.025 |  | Width | Imp | Width | Imp |  | Width | Space | Imp | Width | Space | Imp | Width | Space | Imp | Width | Space | Imp | Width | Space | Imp | Width | Space | Imp | Width | Space | Imp | Width | Space | Imp | Width | Space | Imp | Width | Space | Imp | Width | Space | Imp | Width | Space | Imp |
| Top | Signal | 3/8 oz+plating | 1.7 |  |  |  |  | S1 | 5(L2) | 50.08 |  |  | S1 | 5.75(L2) | 6.5 | 85.36 |  |  |  | 4.9(L2) | 11.1 | 96.82 |  |  |  | 3.5(L2) | 4 |  |  |  |  |  |  |  |  |  |  | 3.75(L2) | 3.5 |  |  |  |  |  |  |  |  |  |  |
|  | Prepreg |  | 3 |  |  | 3.9 | 0.006 |  |  |  |  |  |  |  |  |  |  |  |  |  |  |  |  |  |  |  |  |  |  |  |  |  |  |  |  |  |  |  |  |  |  |  |  |  |  |  |  |  |  |
| L2 | GND | 1 oz | 1.3 |  |  |  |  | P2 | reference layer |  |  |  | P2 | reference layer |  |  |  |  |  | reference layer |  |  |  |  |  | reference layer |  |  |  |  |  | reference layer |  |  |  |  |  | reference layer |  |  |  |  |  | reference layer |  |  |  |  |  |
|  | Core |  | 4 |  |  | 3.9 | 0.006 |  |  |  |  |  |  |  |  |  |  |  |  |  |  |  |  |  |  |  |  |  |  |  |  |  |  |  |  |  |  |  |  |  |  |  |  |  |  |  |  |  |  |
| L3 | Signal | 1 oz | 1.3 |  |  |  |  | S3 | 5(L2/L4) | 49.28 |  |  | S3 | 5.5(L2/L4) | 7.5 | 84.9 |  |  |  | 4(L2/L4) | 8 | 97.59 |  |  |  |  |  |  |  |  |  | 3.5(L2/L4) | 4 |  |  |  |  |  |  |  |  |  |  | 3.75(L2/L4) | 3.5 |  |  |  |  |
|  | Prepreg |  | 16.4 |  |  | 4.2 | 0.006 |  |  |  |  |  |  |  |  |  |  |  |  |  |  |  |  |  |  |  |  |  |  |  |  |  |  |  |  |  |  |  |  |  |  |  |  |  |  |  |  |  |  |
| L4 | POWER | 1 oz | 1.3 |  |  |  |  | P4 | reference layer |  |  |  | P4 | reference layer |  |  |  |  |  | reference layer |  |  |  |  |  | reference layer |  |  |  |  |  | reference layer |  |  |  |  |  | reference layer |  |  |  |  |  | reference layer |  |  |  |  |  |
|  | Core |  | 4 |  |  | 3.8 | 0.006 |  |  |  |  |  |  |  |  |  |  |  |  |  |  |  |  |  |  |  |  |  |  |  |  |  |  |  |  |  |  |  |  |  |  |  |  |  |  |  |  |  |  |
| L5 | POWER | 1 oz | 1.3 | 0 | 0 |  |  | P5 | reference layer |  |  |  | P5 | reference layer |  |  |  |  |  | reference layer |  |  |  |  |  | reference layer |  |  |  |  |  | reference layer |  |  |  |  |  | reference layer |  |  |  |  |  | reference layer |  |  |  |  |  |
|  | Prepreg |  | 16.4 | 0 | 0 | 4.2 | 0.006 |  |  |  |  |  |  |  |  |  |  |  |  |  |  |  |  |  |  |  |  |  |  |  |  |  |  |  |  |  |  |  |  |  |  |  |  |  |  |  |  |  |  |
| L6 | Signal | 1 oz | 1.3 | 0 | 0 |  |  | S6 | 5(L5/L7) | 49.28 |  |  | S6 | 5.5(L5/L7) | 7.5 | 84.9 |  |  |  | 4(L5/L7) | 8 | 97.59 |  |  |  |  |  |  |  |  |  | 3.5(L5/L7) | 4 |  |  |  |  |  |  |  |  |  |  | 3.75(L5/L7) | 3.5 |  |  |  |  |
|  | Core |  | 4 | 0 | 0 | 3.9 | 0.006 |  |  |  |  |  |  |  |  |  |  |  |  |  |  |  |  |  |  |  |  |  |  |  |  |  |  |  |  |  |  |  |  |  |  |  |  |  |  |  |  |  |  |
| L7 | GND | 1 oz | 1.3 | 0 | 0 |  |  | P7 | reference layer |  |  |  | P7 | reference layer |  |  |  |  |  | reference layer |  |  |  |  |  | reference layer |  |  |  |  |  | reference layer |  |  |  |  |  | reference layer |  |  |  |  |  | reference layer |  |  |  |  |  |
|  | Prepreg |  | 3 | 0 | 0 | 3.9 | 0.006 |  |  |  |  |  |  |  |  |  |  |  |  |  |  |  |  |  |  |  |  |  |  |  |  |  |  |  |  |  |  |  |  |  |  |  |  |  |  |  |  |  |  |
| Bottom | Signal | 3/8 oz+plating | 1.7 | 0 | 0 |  |  | S8 | 5(L7) | 50.08 |  |  | S8 | 5.75(L7) | 6.5 | 85.36 |  |  |  | 4.9(L7) | 11.1 | 96.82 |  |  |  | 3.5(L7) | 4 |  |  |  |  |  |  |  |  |  |  | 3.75(L7) | 3.5 |  |  |  |  |  |  |  |  |  |  |
|  | Mask |  | 0.5 | 0 |  | 3.4 | 0.025 |  |  |  |  |  |  |  |  |  |  |  |  |  |  |  |  |  |  |  |  |  |  |  |  |  |  |  |  |  |  |  |  |  |  |  |  |  |  |  |  |  |  |
| Thickness requirement: 1.6 ± 10% mm |  | mil | 62.99999999999999 |  |  |  |  |  |  |  |  |  |  |  |  |  |  |  |  |  |  |  |  |  |  |  |  |  |  |  |  |  |  |  |  |  |  |  |  |  |  |  |  |  |  |  |  |  |  |
|  |  | mm | 1.6002032004064006 |  |  |  |  |  |  |  |  |  |  |  |  |  |  |  |  |  |  |  |  |  |  |  |  |  |  |  |  |  |  |  |  |  |  |  |  |  |  |  |  |  |  |  |  |  |  |
| Note: | 1. Unit is mil |  |  |  |  |  |  |  |  |  |  |  |  |  |  |  |  |  |  |  |  |  |  |  |  |  |  |  |  |  |  |  |  |  |  |  |  |  |  |  |  |  |  |  |  |  |  |  |  |
|  | 2. The total thickness includes trace and solder mask. |  |  |  |  |  |  |  |  |  |  |  |  |  |  |  |  |  |  |  |  |  |  |  |  |  |  |  |  |  |  |  |  |  |  |  |  |  |  |  |  |  |  |  |  |  |  |  |  |
|  | 3. Minimum hole copper thickness is 1.0 mil. |  |  |  |  |  |  |  |  |  |  |  |  |  |  |  |  |  |  |  |  |  |  |  |  |  |  |  |  |  |  |  |  |  |  |  |  |  |  |  |  |  |  |  |  |  |  |  |  |
|  | 4. Minimum surface copper thickness 1.5 mil. |  |  |  |  |  |  |  |  |  |  |  |  |  |  |  |  |  |  |  |  |  |  |  |  |  |  |  |  |  |  |  |  |  |  |  |  |  |  |  |  |  |  |  |  |  |  |  |  |
|  | 5. If there is no controlled impedance line described as the stackup in the gerber file, PCB supplier can ignore this kind of impedance control directly, but need to inform Wiwynn in engineering question(EQ). |  |  |  |  |  |  |  |  |  |  |  |  |  |  |  |  |  |  |  |  |  |  |  |  |  |  |  |  |  |  |  |  |  |  |  |  |  |  |  |  |  |  |  |  |  |  |  |  |
|  | 6. PCB test coupon requirement and PCB test note are described in the another sheets. |  |  |  |  |  |  |  |  |  |  |  |  |  |  |  |  |  |  |  |  |  |  |  |  |  |  |  |  |  |  |  |  |  |  |  |  |  |  |  |  |  |  |  |  |  |  |  |  |
|  | 7. If there is no "Delta-L" design in gerber file, PCB supplier should design 85 ohm "Delta-L" angle routing coupon and provide the measurement results in FAI report which meet the following criteria: |  |  |  |  |  |  |  |  |  |  |  |  |  |  |  |  |  |  |  |  |  |  |  |  |  |  |  |  |  |  |  |  |  |  |  |  |  |  |  |  |  |  |  |  |  |  |  |  |
|  | For low-loss material |  |  |  |  |  |  |  |  |  |  |  |  |  |  |  |  |  |  |  |  |  |  |  |  |  |  |  |  |  |  |  |  |  |  |  |  |  |  |  |  |  |  |  |  |  |  |  |  |
|  | (1)   0.55 dB/inch @ 4GHz; 1.05 dB/inch @ 8GHz for microstrip routing |  |  |  |  |  |  |  |  |  |  |  |  |  |  |  |  |  |  |  |  |  |  |  |  |  |  |  |  |  |  |  |  |  |  |  |  |  |  |  |  |  |  |  |  |  |  |  |  |
|  | (2)   0.48 dB/inch @ 4GHz; 0.9 dB/inch @ 8GHz for stripline routing |  |  |  |  |  |  |  |  |  |  |  |  |  |  |  |  |  |  |  |  |  |  |  |  |  |  |  |  |  |  |  |  |  |  |  |  |  |  |  |  |  |  |  |  |  |  |  |  |
